(kicad_pcb
	(version 20260206)
	(generator "pcbnew")
	(generator_version "10.0")
	(general
		(thickness 1.6)
		(legacy_teardrops no)
	)
	(paper "A4")
	(title_block
		(title "01162023_DA0F0TEBIF0_F0T_Expander_BD_F_brd_V02_OCP.brd")
		(comment 1 "Grand Teton / footprints 7129-7136 of 9728")
	)
	(layers
		(0 "F.Cu" signal "TOP")
		(4 "In1.Cu" signal "GND")
		(6 "In2.Cu" signal "VCC")
		(8 "In3.Cu" signal "VCC1")
		(10 "In4.Cu" signal "GND1")
		(12 "In5.Cu" signal "IN1")
		(14 "In6.Cu" signal "GND2")
		(16 "In7.Cu" signal "IN2")
		(18 "In8.Cu" signal "GND3")
		(20 "In9.Cu" signal "IN3")
		(22 "In10.Cu" signal "GND4")
		(24 "In11.Cu" signal "IN4")
		(26 "In12.Cu" signal "GND5")
		(28 "In13.Cu" signal "IN5")
		(30 "In14.Cu" signal "GND6")
		(32 "In15.Cu" signal "IN6")
		(34 "In16.Cu" signal "GND7")
		(2 "B.Cu" signal "BOTTOM")
		(9 "F.Adhes" user "F.Adhesive")
		(11 "B.Adhes" user "B.Adhesive")
		(13 "F.Paste" user "Package Geometry/Pastemask Top")
		(15 "B.Paste" user "Package Geometry/Pastemask Bottom")
		(5 "F.SilkS" user "Ref Des/Silkscreen Top")
		(7 "B.SilkS" user "Ref Des/Silkscreen Bottom")
		(1 "F.Mask" user "Board Geometry/Soldermask Top")
		(3 "B.Mask" user "Board Geometry/Soldermask Bottom")
		(17 "Dwgs.User" user "User.Drawings")
		(19 "Cmts.User" user "User.Comments")
		(21 "Eco1.User" user "User.Eco1")
		(23 "Eco2.User" user "User.Eco2")
		(25 "Edge.Cuts" user "Board Geometry/Outline")
		(27 "Margin" user)
		(31 "F.CrtYd" user "Package Geometry/Place Bound Top")
		(29 "B.CrtYd" user "Package Geometry/Place Bound Bottom")
		(35 "F.Fab" user "Ref Des/Assembly Top")
		(33 "B.Fab" user "Ref Des/Assembly Bottom")
	)
	(footprint ""
		(layer "B.Cu")
		(at 47.77486 -298.00804 90)
		(property "Reference" "C3068"
			(at 0 0 90)
			(layer "B.SilkS")
			(hide yes)
			(effects
				(font
					(size 1.27 1.27)
				)
				(justify mirror)
			)
		)
		(property "Value" ""
			(at 0 0 90)
			(layer "B.Fab")
			(effects
				(font
					(size 1.27 1.27)
				)
				(justify mirror)
			)
		)
		(duplicate_pad_numbers_are_jumpers no)
		(fp_line
			(start 0.299974 -0.150114)
			(end -0.299974 -0.150114)
			(stroke
				(width 0.1)
				(type default)
			)
			(layer "B.Fab")
		)
		(fp_line
			(start -0.299974 -0.150114)
			(end -0.299974 0.150114)
			(stroke
				(width 0.1)
				(type default)
			)
			(layer "B.Fab")
		)
		(fp_line
			(start 0.299974 0.150114)
			(end 0.299974 -0.150114)
			(stroke
				(width 0.1)
				(type default)
			)
			(layer "B.Fab")
		)
		(fp_line
			(start -0.299974 0.150114)
			(end 0.299974 0.150114)
			(stroke
				(width 0.1)
				(type default)
			)
			(layer "B.Fab")
		)
		(pad "1" smd rect
			(at 0.2667 0 270)
			(size 0.3048 0.381)
			(layers "B.Cu" "B.Mask" "B.Paste")
			(net "SYSPLL_VDDA18_PEX0")
		)
		(pad "2" smd rect
			(at -0.2667 0 270)
			(size 0.3048 0.381)
			(layers "B.Cu" "B.Mask" "B.Paste")
			(net "GND")
		)
	)
	(footprint ""
		(layer "B.Cu")
		(at 294.69969 -303.499774 -90)
		(property "Reference" "C3254"
			(at 0 0 90)
			(layer "B.SilkS")
			(hide yes)
			(effects
				(font
					(size 1.27 1.27)
				)
				(justify mirror)
			)
		)
		(property "Value" ""
			(at 0 0 90)
			(layer "B.Fab")
			(effects
				(font
					(size 1.27 1.27)
				)
				(justify mirror)
			)
		)
		(duplicate_pad_numbers_are_jumpers no)
		(fp_line
			(start -0.299974 0.150114)
			(end 0.299974 0.150114)
			(stroke
				(width 0.1)
				(type default)
			)
			(layer "B.Fab")
		)
		(fp_line
			(start 0.299974 0.150114)
			(end 0.299974 -0.150114)
			(stroke
				(width 0.1)
				(type default)
			)
			(layer "B.Fab")
		)
		(fp_line
			(start -0.299974 -0.150114)
			(end -0.299974 0.150114)
			(stroke
				(width 0.1)
				(type default)
			)
			(layer "B.Fab")
		)
		(fp_line
			(start 0.299974 -0.150114)
			(end -0.299974 -0.150114)
			(stroke
				(width 0.1)
				(type default)
			)
			(layer "B.Fab")
		)
		(pad "1" smd rect
			(at 0.2667 0 90)
			(size 0.3048 0.381)
			(layers "B.Cu" "B.Mask" "B.Paste")
			(net "P1V25_PEX2")
		)
		(pad "2" smd rect
			(at -0.2667 0 90)
			(size 0.3048 0.381)
			(layers "B.Cu" "B.Mask" "B.Paste")
			(net "GND")
		)
	)
	(footprint ""
		(layer "B.Cu")
		(at 406.999948 -288.299906 90)
		(property "Reference" "C3457"
			(at 0 0 90)
			(layer "B.SilkS")
			(hide yes)
			(effects
				(font
					(size 1.27 1.27)
				)
				(justify mirror)
			)
		)
		(property "Value" ""
			(at 0 0 90)
			(layer "B.Fab")
			(effects
				(font
					(size 1.27 1.27)
				)
				(justify mirror)
			)
		)
		(duplicate_pad_numbers_are_jumpers no)
		(fp_line
			(start 0.299974 -0.150114)
			(end -0.299974 -0.150114)
			(stroke
				(width 0.1)
				(type default)
			)
			(layer "B.Fab")
		)
		(fp_line
			(start -0.299974 -0.150114)
			(end -0.299974 0.150114)
			(stroke
				(width 0.1)
				(type default)
			)
			(layer "B.Fab")
		)
		(fp_line
			(start 0.299974 0.150114)
			(end 0.299974 -0.150114)
			(stroke
				(width 0.1)
				(type default)
			)
			(layer "B.Fab")
		)
		(fp_line
			(start -0.299974 0.150114)
			(end 0.299974 0.150114)
			(stroke
				(width 0.1)
				(type default)
			)
			(layer "B.Fab")
		)
		(pad "1" smd rect
			(at 0.2667 0 270)
			(size 0.3048 0.381)
			(layers "B.Cu" "B.Mask" "B.Paste")
			(net "P1V25_PEX3")
		)
		(pad "2" smd rect
			(at -0.2667 0 270)
			(size 0.3048 0.381)
			(layers "B.Cu" "B.Mask" "B.Paste")
			(net "GND")
		)
	)
	(footprint ""
		(layer "B.Cu")
		(at 335.82737 -85.75421 180)
		(property "Reference" "C2675"
			(at 0 0 0)
			(layer "B.SilkS")
			(hide yes)
			(effects
				(font
					(size 1.27 1.27)
				)
				(justify mirror)
			)
		)
		(property "Value" ""
			(at 0 0 0)
			(layer "B.Fab")
			(effects
				(font
					(size 1.27 1.27)
				)
				(justify mirror)
			)
		)
		(duplicate_pad_numbers_are_jumpers no)
		(fp_line
			(start 0.7874 0.4064)
			(end 0.7874 -0.4064)
			(stroke
				(width 0.1524)
				(type default)
			)
			(layer "B.SilkS")
		)
		(fp_line
			(start 0.7874 -0.4064)
			(end -0.7874 -0.4064)
			(stroke
				(width 0.1524)
				(type default)
			)
			(layer "B.SilkS")
		)
		(fp_line
			(start -0.7874 0.4064)
			(end 0.7874 0.4064)
			(stroke
				(width 0.1524)
				(type default)
			)
			(layer "B.SilkS")
		)
		(fp_line
			(start -0.7874 -0.4064)
			(end -0.7874 0.4064)
			(stroke
				(width 0.1524)
				(type default)
			)
			(layer "B.SilkS")
		)
		(fp_line
			(start 0.67945 0.3048)
			(end 0.67945 -0.305054)
			(stroke
				(width 0.1)
				(type default)
			)
			(layer "B.Fab")
		)
		(fp_line
			(start 0.67945 -0.305054)
			(end 0.12065 -0.305054)
			(stroke
				(width 0.1)
				(type default)
			)
			(layer "B.Fab")
		)
		(fp_line
			(start 0.12065 0.3048)
			(end 0.67945 0.3048)
			(stroke
				(width 0.1)
				(type default)
			)
			(layer "B.Fab")
		)
		(fp_line
			(start 0.12065 0.2794)
			(end 0.12065 0.3048)
			(stroke
				(width 0.1)
				(type default)
			)
			(layer "B.Fab")
		)
		(fp_line
			(start 0.12065 -0.2794)
			(end -0.12065 -0.2794)
			(stroke
				(width 0.1)
				(type default)
			)
			(layer "B.Fab")
		)
		(fp_line
			(start 0.12065 -0.305054)
			(end 0.12065 -0.2794)
			(stroke
				(width 0.1)
				(type default)
			)
			(layer "B.Fab")
		)
		(fp_line
			(start -0.120396 0.3048)
			(end -0.120396 0.2794)
			(stroke
				(width 0.1)
				(type default)
			)
			(layer "B.Fab")
		)
		(fp_line
			(start -0.120396 0.2794)
			(end 0.12065 0.2794)
			(stroke
				(width 0.1)
				(type default)
			)
			(layer "B.Fab")
		)
		(fp_line
			(start -0.12065 -0.2794)
			(end -0.12065 -0.3048)
			(stroke
				(width 0.1)
				(type default)
			)
			(layer "B.Fab")
		)
		(fp_line
			(start -0.12065 -0.3048)
			(end -0.67945 -0.3048)
			(stroke
				(width 0.1)
				(type default)
			)
			(layer "B.Fab")
		)
		(fp_line
			(start -0.67945 0.3048)
			(end -0.120396 0.3048)
			(stroke
				(width 0.1)
				(type default)
			)
			(layer "B.Fab")
		)
		(fp_line
			(start -0.67945 -0.3048)
			(end -0.67945 0.3048)
			(stroke
				(width 0.1)
				(type default)
			)
			(layer "B.Fab")
		)
		(pad "1" smd circle
			(at 0.40005 0)
			(size 0 0)
			(layers "B.Cu" "B.Mask" "B.Paste")
			(net "P3V3_VDD_9ZXL0851_8_15")
		)
		(pad "2" smd circle
			(at -0.40005 0)
			(size 0 0)
			(layers "B.Cu" "B.Mask" "B.Paste")
			(net "GND")
		)
	)
	(footprint ""
		(layer "B.Cu")
		(at 288.206942 -136.652 -90)
		(property "Reference" "R240"
			(at 0 0 90)
			(layer "B.SilkS")
			(hide yes)
			(effects
				(font
					(size 1.27 1.27)
				)
				(justify mirror)
			)
		)
		(property "Value" ""
			(at 0 0 90)
			(layer "B.Fab")
			(effects
				(font
					(size 1.27 1.27)
				)
				(justify mirror)
			)
		)
		(duplicate_pad_numbers_are_jumpers no)
		(fp_line
			(start -0.7874 0.4064)
			(end 0.7874 0.4064)
			(stroke
				(width 0.1524)
				(type default)
			)
			(layer "B.SilkS")
		)
		(fp_line
			(start 0.7874 0.4064)
			(end 0.7874 -0.4064)
			(stroke
				(width 0.1524)
				(type default)
			)
			(layer "B.SilkS")
		)
		(fp_line
			(start -0.7874 -0.4064)
			(end -0.7874 0.4064)
			(stroke
				(width 0.1524)
				(type default)
			)
			(layer "B.SilkS")
		)
		(fp_line
			(start 0.7874 -0.4064)
			(end -0.7874 -0.4064)
			(stroke
				(width 0.1524)
				(type default)
			)
			(layer "B.SilkS")
		)
		(fp_line
			(start -0.67945 0.3048)
			(end -0.120396 0.3048)
			(stroke
				(width 0.1)
				(type default)
			)
			(layer "B.Fab")
		)
		(fp_line
			(start -0.120396 0.3048)
			(end -0.120396 0.2794)
			(stroke
				(width 0.1)
				(type default)
			)
			(layer "B.Fab")
		)
		(fp_line
			(start 0.12065 0.3048)
			(end 0.67945 0.3048)
			(stroke
				(width 0.1)
				(type default)
			)
			(layer "B.Fab")
		)
		(fp_line
			(start 0.67945 0.3048)
			(end 0.67945 -0.305054)
			(stroke
				(width 0.1)
				(type default)
			)
			(layer "B.Fab")
		)
		(fp_line
			(start -0.120396 0.2794)
			(end 0.12065 0.2794)
			(stroke
				(width 0.1)
				(type default)
			)
			(layer "B.Fab")
		)
		(fp_line
			(start 0.12065 0.2794)
			(end 0.12065 0.3048)
			(stroke
				(width 0.1)
				(type default)
			)
			(layer "B.Fab")
		)
		(fp_line
			(start -0.12065 -0.2794)
			(end -0.12065 -0.3048)
			(stroke
				(width 0.1)
				(type default)
			)
			(layer "B.Fab")
		)
		(fp_line
			(start 0.12065 -0.2794)
			(end -0.12065 -0.2794)
			(stroke
				(width 0.1)
				(type default)
			)
			(layer "B.Fab")
		)
		(fp_line
			(start -0.67945 -0.3048)
			(end -0.67945 0.3048)
			(stroke
				(width 0.1)
				(type default)
			)
			(layer "B.Fab")
		)
		(fp_line
			(start -0.12065 -0.3048)
			(end -0.67945 -0.3048)
			(stroke
				(width 0.1)
				(type default)
			)
			(layer "B.Fab")
		)
		(fp_line
			(start 0.12065 -0.305054)
			(end 0.12065 -0.2794)
			(stroke
				(width 0.1)
				(type default)
			)
			(layer "B.Fab")
		)
		(fp_line
			(start 0.67945 -0.305054)
			(end 0.12065 -0.305054)
			(stroke
				(width 0.1)
				(type default)
			)
			(layer "B.Fab")
		)
		(pad "1" smd circle
			(at 0.40005 0 90)
			(size 0 0)
			(layers "B.Cu" "B.Mask" "B.Paste")
			(net "RST_SMB_NIC_MUX_R_N")
		)
		(pad "2" smd circle
			(at -0.40005 0 90)
			(size 0 0)
			(layers "B.Cu" "B.Mask" "B.Paste")
			(net "RST_SMB_NIC4_MUX_N")
		)
	)
	(footprint ""
		(layer "B.Cu")
		(at 222.212154 -197.791832 -90)
		(property "Reference" "R1024"
			(at 0 0 90)
			(layer "B.SilkS")
			(hide yes)
			(effects
				(font
					(size 1.27 1.27)
				)
				(justify mirror)
			)
		)
		(property "Value" ""
			(at 0 0 90)
			(layer "B.Fab")
			(effects
				(font
					(size 1.27 1.27)
				)
				(justify mirror)
			)
		)
		(duplicate_pad_numbers_are_jumpers no)
		(fp_line
			(start -0.7874 0.4064)
			(end 0.7874 0.4064)
			(stroke
				(width 0.1524)
				(type default)
			)
			(layer "B.SilkS")
		)
		(fp_line
			(start 0.7874 0.4064)
			(end 0.7874 -0.4064)
			(stroke
				(width 0.1524)
				(type default)
			)
			(layer "B.SilkS")
		)
		(fp_line
			(start -0.7874 -0.4064)
			(end -0.7874 0.4064)
			(stroke
				(width 0.1524)
				(type default)
			)
			(layer "B.SilkS")
		)
		(fp_line
			(start 0.7874 -0.4064)
			(end -0.7874 -0.4064)
			(stroke
				(width 0.1524)
				(type default)
			)
			(layer "B.SilkS")
		)
		(fp_line
			(start -0.67945 0.3048)
			(end -0.120396 0.3048)
			(stroke
				(width 0.1)
				(type default)
			)
			(layer "B.Fab")
		)
		(fp_line
			(start -0.120396 0.3048)
			(end -0.120396 0.2794)
			(stroke
				(width 0.1)
				(type default)
			)
			(layer "B.Fab")
		)
		(fp_line
			(start 0.12065 0.3048)
			(end 0.67945 0.3048)
			(stroke
				(width 0.1)
				(type default)
			)
			(layer "B.Fab")
		)
		(fp_line
			(start 0.67945 0.3048)
			(end 0.67945 -0.305054)
			(stroke
				(width 0.1)
				(type default)
			)
			(layer "B.Fab")
		)
		(fp_line
			(start -0.120396 0.2794)
			(end 0.12065 0.2794)
			(stroke
				(width 0.1)
				(type default)
			)
			(layer "B.Fab")
		)
		(fp_line
			(start 0.12065 0.2794)
			(end 0.12065 0.3048)
			(stroke
				(width 0.1)
				(type default)
			)
			(layer "B.Fab")
		)
		(fp_line
			(start -0.12065 -0.2794)
			(end -0.12065 -0.3048)
			(stroke
				(width 0.1)
				(type default)
			)
			(layer "B.Fab")
		)
		(fp_line
			(start 0.12065 -0.2794)
			(end -0.12065 -0.2794)
			(stroke
				(width 0.1)
				(type default)
			)
			(layer "B.Fab")
		)
		(fp_line
			(start -0.67945 -0.3048)
			(end -0.67945 0.3048)
			(stroke
				(width 0.1)
				(type default)
			)
			(layer "B.Fab")
		)
		(fp_line
			(start -0.12065 -0.3048)
			(end -0.67945 -0.3048)
			(stroke
				(width 0.1)
				(type default)
			)
			(layer "B.Fab")
		)
		(fp_line
			(start 0.12065 -0.305054)
			(end 0.12065 -0.2794)
			(stroke
				(width 0.1)
				(type default)
			)
			(layer "B.Fab")
		)
		(fp_line
			(start 0.67945 -0.305054)
			(end 0.12065 -0.305054)
			(stroke
				(width 0.1)
				(type default)
			)
			(layer "B.Fab")
		)
		(pad "1" smd circle
			(at 0.40005 0 90)
			(size 0 0)
			(layers "B.Cu" "B.Mask" "B.Paste")
			(net "SPI_BIC1_MOSI_R")
		)
		(pad "2" smd circle
			(at -0.40005 0 90)
			(size 0 0)
			(layers "B.Cu" "B.Mask" "B.Paste")
			(net "SPI_BIC1_MOSI_R5")
		)
	)
	(footprint ""
		(layer "B.Cu")
		(at 354.78212 -228.348794 90)
		(property "Reference" "R5636"
			(at 0 0 90)
			(layer "B.SilkS")
			(hide yes)
			(effects
				(font
					(size 1.27 1.27)
				)
				(justify mirror)
			)
		)
		(property "Value" ""
			(at 0 0 90)
			(layer "B.Fab")
			(effects
				(font
					(size 1.27 1.27)
				)
				(justify mirror)
			)
		)
		(duplicate_pad_numbers_are_jumpers no)
		(fp_line
			(start 1.2954 -0.5842)
			(end -1.2954 -0.5842)
			(stroke
				(width 0.1524)
				(type default)
			)
			(layer "B.SilkS")
		)
		(fp_line
			(start -1.2954 -0.5842)
			(end -1.2954 0.5842)
			(stroke
				(width 0.1524)
				(type default)
			)
			(layer "B.SilkS")
		)
		(fp_line
			(start 1.2954 0.5842)
			(end 1.2954 -0.5842)
			(stroke
				(width 0.1524)
				(type default)
			)
			(layer "B.SilkS")
		)
		(fp_line
			(start -1.2954 0.5842)
			(end 1.2954 0.5842)
			(stroke
				(width 0.1524)
				(type default)
			)
			(layer "B.SilkS")
		)
		(fp_line
			(start 0.8636 -0.4572)
			(end -0.8636 -0.4572)
			(stroke
				(width 0.1)
				(type default)
			)
			(layer "B.Fab")
		)
		(fp_line
			(start -0.8636 -0.4572)
			(end -0.8636 -0.406654)
			(stroke
				(width 0.1)
				(type default)
			)
			(layer "B.Fab")
		)
		(fp_line
			(start 1.1938 -0.406654)
			(end 0.8636 -0.406654)
			(stroke
				(width 0.1)
				(type default)
			)
			(layer "B.Fab")
		)
		(fp_line
			(start 0.8636 -0.406654)
			(end 0.8636 -0.4572)
			(stroke
				(width 0.1)
				(type default)
			)
			(layer "B.Fab")
		)
		(fp_line
			(start -0.8636 -0.406654)
			(end -1.1938 -0.406654)
			(stroke
				(width 0.1)
				(type default)
			)
			(layer "B.Fab")
		)
		(fp_line
			(start -1.1938 -0.406654)
			(end -1.1938 0.4064)
			(stroke
				(width 0.1)
				(type default)
			)
			(layer "B.Fab")
		)
		(fp_line
			(start 1.1938 0.4064)
			(end 1.1938 -0.406654)
			(stroke
				(width 0.1)
				(type default)
			)
			(layer "B.Fab")
		)
		(fp_line
			(start 0.8636 0.4064)
			(end 1.1938 0.4064)
			(stroke
				(width 0.1)
				(type default)
			)
			(layer "B.Fab")
		)
		(fp_line
			(start -0.8636 0.4064)
			(end -0.8636 0.4572)
			(stroke
				(width 0.1)
				(type default)
			)
			(layer "B.Fab")
		)
		(fp_line
			(start -1.1938 0.4064)
			(end -0.8636 0.4064)
			(stroke
				(width 0.1)
				(type default)
			)
			(layer "B.Fab")
		)
		(fp_line
			(start 0.8636 0.4318)
			(end 0.8636 0.4064)
			(stroke
				(width 0.1)
				(type default)
			)
			(layer "B.Fab")
		)
		(fp_line
			(start 0.8636 0.4572)
			(end 0.8636 0.4318)
			(stroke
				(width 0.1)
				(type default)
			)
			(layer "B.Fab")
		)
		(fp_line
			(start -0.8636 0.4572)
			(end 0.8636 0.4572)
			(stroke
				(width 0.1)
				(type default)
			)
			(layer "B.Fab")
		)
		(pad "1" smd rect
			(at 0.7366 0)
			(size 0.7112 0.8128)
			(layers "B.Cu" "B.Mask" "B.Paste")
			(net "P3V3_AUX")
		)
		(pad "2" smd rect
			(at -0.7366 0)
			(size 0.7112 0.8128)
			(layers "B.Cu" "B.Mask" "B.Paste")
			(net "P3V3_FPGA_VCCIO0")
		)
	)
	(footprint ""
		(layer "B.Cu")
		(at 351.547684 -303.141634)
		(property "Reference" "PR128"
			(at 0 0 0)
			(layer "B.SilkS")
			(hide yes)
			(effects
				(font
					(size 1.27 1.27)
				)
				(justify mirror)
			)
		)
		(property "Value" ""
			(at 0 0 0)
			(layer "B.Fab")
			(effects
				(font
					(size 1.27 1.27)
				)
				(justify mirror)
			)
		)
		(duplicate_pad_numbers_are_jumpers no)
		(fp_line
			(start -0.7874 -0.4064)
			(end -0.7874 0.4064)
			(stroke
				(width 0.1524)
				(type default)
			)
			(layer "B.SilkS")
		)
		(fp_line
			(start -0.7874 0.4064)
			(end 0.7874 0.4064)
			(stroke
				(width 0.1524)
				(type default)
			)
			(layer "B.SilkS")
		)
		(fp_line
			(start 0.7874 -0.4064)
			(end -0.7874 -0.4064)
			(stroke
				(width 0.1524)
				(type default)
			)
			(layer "B.SilkS")
		)
		(fp_line
			(start 0.7874 0.4064)
			(end 0.7874 -0.4064)
			(stroke
				(width 0.1524)
				(type default)
			)
			(layer "B.SilkS")
		)
		(fp_line
			(start -0.67945 -0.3048)
			(end -0.67945 0.3048)
			(stroke
				(width 0.1)
				(type default)
			)
			(layer "B.Fab")
		)
		(fp_line
			(start -0.67945 0.3048)
			(end -0.120396 0.3048)
			(stroke
				(width 0.1)
				(type default)
			)
			(layer "B.Fab")
		)
		(fp_line
			(start -0.12065 -0.3048)
			(end -0.67945 -0.3048)
			(stroke
				(width 0.1)
				(type default)
			)
			(layer "B.Fab")
		)
		(fp_line
			(start -0.12065 -0.2794)
			(end -0.12065 -0.3048)
			(stroke
				(width 0.1)
				(type default)
			)
			(layer "B.Fab")
		)
		(fp_line
			(start -0.120396 0.2794)
			(end 0.12065 0.2794)
			(stroke
				(width 0.1)
				(type default)
			)
			(layer "B.Fab")
		)
		(fp_line
			(start -0.120396 0.3048)
			(end -0.120396 0.2794)
			(stroke
				(width 0.1)
				(type default)
			)
			(layer "B.Fab")
		)
		(fp_line
			(start 0.12065 -0.305054)
			(end 0.12065 -0.2794)
			(stroke
				(width 0.1)
				(type default)
			)
			(layer "B.Fab")
		)
		(fp_line
			(start 0.12065 -0.2794)
			(end -0.12065 -0.2794)
			(stroke
				(width 0.1)
				(type default)
			)
			(layer "B.Fab")
		)
		(fp_line
			(start 0.12065 0.2794)
			(end 0.12065 0.3048)
			(stroke
				(width 0.1)
				(type default)
			)
			(layer "B.Fab")
		)
		(fp_line
			(start 0.12065 0.3048)
			(end 0.67945 0.3048)
			(stroke
				(width 0.1)
				(type default)
			)
			(layer "B.Fab")
		)
		(fp_line
			(start 0.67945 -0.305054)
			(end 0.12065 -0.305054)
			(stroke
				(width 0.1)
				(type default)
			)
			(layer "B.Fab")
		)
		(fp_line
			(start 0.67945 0.3048)
			(end 0.67945 -0.305054)
			(stroke
				(width 0.1)
				(type default)
			)
			(layer "B.Fab")
		)
		(pad "1" smd circle
			(at 0.40005 0 180)
			(size 0 0)
			(layers "B.Cu" "B.Mask" "B.Paste")
			(net "P0V8_PEX3")
		)
		(pad "2" smd circle
			(at -0.40005 0 180)
			(size 0 0)
			(layers "B.Cu" "B.Mask" "B.Paste")
			(net "SH_P0V8_PEX3_VSEN3_L")
		)
	)
)
